# BASEBOARD_FAB2 (Tioga Pass) — schematic netlist excerpt (pin names and nets, part order shuffled) for the footprints in the layout excerpt that follows; sources: Cadence DE-HDL packaged netlist, KiCad conversion of Wiwynn_Tioga_Pass_MB.brd

R25W114  RES  4.75K 1% EMPTY  pkg 0402  page 150 : A = P3V3_STBY ; B = TP_RGMII1TXD2_GPIOT4
R1C2  RES  0.0 5% CHIP  pkg 0402  page 55 : A = SVID_DIO1_CPU1 ; B = SVID_DIO1_CPU1_R
C3N30  CAP_A  22.0UF 4V 20% X6S  pkg 0603V  page 132 : A = PVNN_PCH_STBY ; B = GND

(kicad_pcb
	(version 20260206)
	(generator "pcbnew")
	(generator_version "10.0")
	(general
		(thickness 1.6)
		(legacy_teardrops no)
	)
	(paper "A4")
	(title_block
		(title "Wiwynn_Tioga_Pass_MB.brd")
		(comment 1 "Tioga Pass / footprints 3320-3322 of 4770")
	)
	(layers
		(0 "F.Cu" signal "TOP")
		(4 "In1.Cu" signal "L2GND")
		(6 "In2.Cu" signal "L3")
		(8 "In3.Cu" signal "L4GND")
		(10 "In4.Cu" signal "L5")
		(12 "In5.Cu" signal "L6GND")
		(14 "In6.Cu" signal "L7VCC")
		(16 "In7.Cu" signal "L8VCC")
		(18 "In8.Cu" signal "L9GND")
		(20 "In9.Cu" signal "L10")
		(22 "In10.Cu" signal "L11GND")
		(24 "In11.Cu" signal "L12")
		(26 "In12.Cu" signal "L13GND")
		(2 "B.Cu" signal "BOTTOM")
		(9 "F.Adhes" user "F.Adhesive")
		(11 "B.Adhes" user "B.Adhesive")
		(13 "F.Paste" user "Package Geometry/Pastemask Top")
		(15 "B.Paste" user "Package Geometry/Pastemask Bottom")
		(5 "F.SilkS" user "Ref Des/Silkscreen Top")
		(7 "B.SilkS" user "Ref Des/Silkscreen Bottom")
		(1 "F.Mask" user "Board Geometry/Soldermask Top")
		(3 "B.Mask" user "Board Geometry/Soldermask Bottom")
		(17 "Dwgs.User" user "User.Drawings")
		(19 "Cmts.User" user "User.Comments")
		(21 "Eco1.User" user "User.Eco1")
		(23 "Eco2.User" user "User.Eco2")
		(25 "Edge.Cuts" user "Board Geometry/Outline")
		(27 "Margin" user)
		(31 "F.CrtYd" user "Package Geometry/Place Bound Top")
		(29 "B.CrtYd" user "Package Geometry/Place Bound Bottom")
		(35 "F.Fab" user "Ref Des/Assembly Top")
		(33 "B.Fab" user "Ref Des/Assembly Bottom")
	)
	(footprint ""
		(layer "B.Cu")
		(at 39.334694 -106.922316 -90)
		(property "Reference" "R1C2"
			(at 0 0 90)
			(layer "B.SilkS")
			(hide yes)
			(effects
				(font
					(size 1.27 1.27)
				)
				(justify mirror)
			)
		)
		(property "Value" ""
			(at 0 0 90)
			(layer "B.Fab")
			(effects
				(font
					(size 1.27 1.27)
				)
				(justify mirror)
			)
		)
		(duplicate_pad_numbers_are_jumpers no)
		(fp_poly
			(pts
				(xy 0.2794 -0.1016) (xy -0.2794 -0.1016) (xy -0.2794 0.9906) (xy 0.2794 0.9906)
			)
			(stroke
				(width 0)
				(type default)
			)
			(fill no)
			(layer "B.CrtYd")
		)
		(fp_line
			(start -0.2794 0.9906)
			(end -0.2794 -0.1016)
			(stroke
				(width 0.1)
				(type default)
			)
			(layer "B.Fab")
		)
		(fp_line
			(start 0.2794 0.9906)
			(end -0.2794 0.9906)
			(stroke
				(width 0.1)
				(type default)
			)
			(layer "B.Fab")
		)
		(fp_line
			(start -0.2794 -0.1016)
			(end 0.2794 -0.1016)
			(stroke
				(width 0.1)
				(type default)
			)
			(layer "B.Fab")
		)
		(fp_line
			(start 0.2794 -0.1016)
			(end 0.2794 0.9906)
			(stroke
				(width 0.1)
				(type default)
			)
			(layer "B.Fab")
		)
		(pad "1" smd rect
			(at 0 0 90)
			(size 0.508 0.508)
			(layers "B.Cu" "B.Mask" "B.Paste")
			(net "SVID_DIO1_CPU1")
		)
		(pad "2" smd rect
			(at 0 0.889 90)
			(size 0.508 0.508)
			(layers "B.Cu" "B.Mask" "B.Paste")
			(net "SVID_DIO1_CPU1_R")
		)
		(zone
			(layer "B.Cu")
			(hatch none 0.5)
			(connect_pads
				(clearance 0)
			)
			(min_thickness 0.25)
			(keepout
				(tracks not_allowed)
				(vias allowed)
				(pads allowed)
				(copperpour not_allowed)
				(footprints allowed)
			)
			(placement
				(enabled no)
				(sheetname "")
			)
			(fill
				(thermal_gap 0.5)
				(thermal_bridge_width 0.5)
				(island_removal_mode 0)
			)
			(polygon
				(pts
					(xy 38.699694 -106.668316) (xy 38.699694 -107.176316) (xy 39.080694 -107.176316) (xy 39.080694 -106.668316)
				)
			)
		)
		(zone
			(layer "B.Cu")
			(hatch none 0.5)
			(connect_pads
				(clearance 0)
			)
			(min_thickness 0.25)
			(keepout
				(tracks allowed)
				(vias not_allowed)
				(pads allowed)
				(copperpour not_allowed)
				(footprints allowed)
			)
			(placement
				(enabled no)
				(sheetname "")
			)
			(fill
				(thermal_gap 0.5)
				(thermal_bridge_width 0.5)
				(island_removal_mode 0)
			)
			(polygon
				(pts
					(xy 39.080694 -106.668316) (xy 39.080694 -107.176316) (xy 38.699694 -107.176316) (xy 38.699694 -106.668316)
				)
			)
		)
	)
	(footprint ""
		(layer "B.Cu")
		(at 370.1669 -103.6066 90)
		(property "Reference" "C3N30"
			(at 0 0 90)
			(layer "B.SilkS")
			(hide yes)
			(effects
				(font
					(size 1.27 1.27)
				)
				(justify mirror)
			)
		)
		(property "Value" ""
			(at 0 0 90)
			(layer "B.Fab")
			(effects
				(font
					(size 1.27 1.27)
				)
				(justify mirror)
			)
		)
		(duplicate_pad_numbers_are_jumpers no)
		(fp_poly
			(pts
				(xy 0.4953 -0.2032) (xy -0.4953 -0.2032) (xy -0.4953 1.6002) (xy 0.4953 1.6002)
			)
			(stroke
				(width 0)
				(type default)
			)
			(fill no)
			(layer "B.CrtYd")
		)
		(fp_line
			(start 0.4953 -0.2032)
			(end -0.4953 -0.2032)
			(stroke
				(width 0.1)
				(type default)
			)
			(layer "B.Fab")
		)
		(fp_line
			(start -0.4953 -0.2032)
			(end -0.4953 1.6002)
			(stroke
				(width 0.1)
				(type default)
			)
			(layer "B.Fab")
		)
		(fp_line
			(start 0.4953 1.6002)
			(end 0.4953 -0.2032)
			(stroke
				(width 0.1)
				(type default)
			)
			(layer "B.Fab")
		)
		(fp_line
			(start -0.4953 1.6002)
			(end 0.4953 1.6002)
			(stroke
				(width 0.1)
				(type default)
			)
			(layer "B.Fab")
		)
		(pad "1" smd rect
			(at 0 0 270)
			(size 0.762 0.889)
			(layers "B.Cu" "B.Mask" "B.Paste")
			(net "PVNN_PCH_STBY")
		)
		(pad "2" smd rect
			(at 0 1.397 270)
			(size 0.762 0.889)
			(layers "B.Cu" "B.Mask" "B.Paste")
			(net "GND")
		)
		(zone
			(layer "B.Cu")
			(hatch none 0.5)
			(connect_pads
				(clearance 0)
			)
			(min_thickness 0.25)
			(keepout
				(tracks not_allowed)
				(vias allowed)
				(pads allowed)
				(copperpour not_allowed)
				(footprints allowed)
			)
			(placement
				(enabled no)
				(sheetname "")
			)
			(fill
				(thermal_gap 0.5)
				(thermal_bridge_width 0.5)
				(island_removal_mode 0)
			)
			(polygon
				(pts
					(xy 370.6114 -103.9876) (xy 370.6114 -103.2256) (xy 371.1194 -103.2256) (xy 371.1194 -103.9876)
				)
			)
		)
	)
	(footprint ""
		(layer "B.Cu")
		(at 404.3045 -30.099 90)
		(property "Reference" "R25W114"
			(at 0.8382 -0.67818 90)
			(unlocked yes)
			(layer "B.SilkS")
			(effects
				(font
					(size 0.4064 0.254)
					(thickness 0.1524)
				)
				(justify left mirror)
			)
		)
		(property "Value" ""
			(at 0 0 90)
			(layer "B.Fab")
			(effects
				(font
					(size 1.27 1.27)
				)
				(justify mirror)
			)
		)
		(duplicate_pad_numbers_are_jumpers no)
		(fp_poly
			(pts
				(xy 0.2794 -0.1016) (xy -0.2794 -0.1016) (xy -0.2794 0.9906) (xy 0.2794 0.9906)
			)
			(stroke
				(width 0)
				(type default)
			)
			(fill no)
			(layer "B.CrtYd")
		)
		(fp_line
			(start 0.2794 -0.1016)
			(end 0.2794 0.9906)
			(stroke
				(width 0.1)
				(type default)
			)
			(layer "B.Fab")
		)
		(fp_line
			(start -0.2794 -0.1016)
			(end 0.2794 -0.1016)
			(stroke
				(width 0.1)
				(type default)
			)
			(layer "B.Fab")
		)
		(fp_line
			(start 0.2794 0.9906)
			(end -0.2794 0.9906)
			(stroke
				(width 0.1)
				(type default)
			)
			(layer "B.Fab")
		)
		(fp_line
			(start -0.2794 0.9906)
			(end -0.2794 -0.1016)
			(stroke
				(width 0.1)
				(type default)
			)
			(layer "B.Fab")
		)
		(pad "1" smd rect
			(at 0 0 270)
			(size 0.508 0.508)
			(layers "B.Cu" "B.Mask" "B.Paste")
			(net "P3V3_STBY")
		)
		(pad "2" smd rect
			(at 0 0.889 270)
			(size 0.508 0.508)
			(layers "B.Cu" "B.Mask" "B.Paste")
			(net "TP_RGMII1TXD2_GPIOT4")
		)
		(zone
			(layer "B.Cu")
			(hatch none 0.5)
			(connect_pads
				(clearance 0)
			)
			(min_thickness 0.25)
			(keepout
				(tracks allowed)
				(vias not_allowed)
				(pads allowed)
				(copperpour not_allowed)
				(footprints allowed)
			)
			(placement
				(enabled no)
				(sheetname "")
			)
			(fill
				(thermal_gap 0.5)
				(thermal_bridge_width 0.5)
				(island_removal_mode 0)
			)
			(polygon
				(pts
					(xy 404.5585 -30.353) (xy 404.5585 -29.845) (xy 404.9395 -29.845) (xy 404.9395 -30.353)
				)
			)
		)
		(zone
			(layer "B.Cu")
			(hatch none 0.5)
			(connect_pads
				(clearance 0)
			)
			(min_thickness 0.25)
			(keepout
				(tracks not_allowed)
				(vias allowed)
				(pads allowed)
				(copperpour not_allowed)
				(footprints allowed)
			)
			(placement
				(enabled no)
				(sheetname "")
			)
			(fill
				(thermal_gap 0.5)
				(thermal_bridge_width 0.5)
				(island_removal_mode 0)
			)
			(polygon
				(pts
					(xy 404.9395 -30.353) (xy 404.9395 -29.845) (xy 404.5585 -29.845) (xy 404.5585 -30.353)
				)
			)
		)
	)
)
